# T6G (Grand Teton) — schematic netlist excerpt (pin names and nets, part order shuffled) for the footprints in the layout excerpt that follows; sources: Cadence DE-HDL packaged netlist, KiCad conversion of 04192023_DAF0TMB3IC0_F0TG_MB_C_brd_V02_OCP.brd

C806  Q_CAP_DIFFBUS  DIFF BUS_0.22UF 6.3V 20% X6S  pkg C0201  page 65 : \1\ = P5E_CPU1_P0_TX_C_DN<15> ; \2\ = P5E_CPU1_P0_TX_DN<15>
R8458  Q_RES  0 5% EMPTY  pkg 0402LF  page 207 : A = P3V3_AUX ; B = PVDD11_S3_P0_VDDIO
R1047  Q_RES  0 5% CHIP  pkg 0201LF  page 298 : A = RST_RT_CPU0_P2_PERST_N ; B = RST_RT_CPU0_P2_PERST_R_N
PC2142  Q_CAP  10UF 16V 10% X6S  pkg C0805  page 140 : A = P3V3_OCP_V3_2_R ; B = GND

(kicad_pcb
	(version 20260206)
	(generator "pcbnew")
	(generator_version "10.0")
	(general
		(thickness 1.6)
		(legacy_teardrops no)
	)
	(paper "A4")
	(title_block
		(title "04192023_DAF0TMB3IC0_F0TG_MB_C_brd_V02_OCP.brd")
		(comment 1 "Grand Teton / footprints 55-58 of 8354")
	)
	(layers
		(0 "F.Cu" signal "TOP")
		(4 "In1.Cu" signal "GND")
		(6 "In2.Cu" signal "IN1")
		(8 "In3.Cu" signal "GND1")
		(10 "In4.Cu" signal "IN2")
		(12 "In5.Cu" signal "GND2")
		(14 "In6.Cu" signal "IN3")
		(16 "In7.Cu" signal "GND3")
		(18 "In8.Cu" signal "VCC")
		(20 "In9.Cu" signal "VCC1")
		(22 "In10.Cu" signal "GND4")
		(24 "In11.Cu" signal "IN4")
		(26 "In12.Cu" signal "GND5")
		(28 "In13.Cu" signal "IN5")
		(30 "In14.Cu" signal "GND6")
		(32 "In15.Cu" signal "IN6")
		(34 "In16.Cu" signal "GND7")
		(2 "B.Cu" signal "BOTTOM")
		(9 "F.Adhes" user "F.Adhesive")
		(11 "B.Adhes" user "B.Adhesive")
		(13 "F.Paste" user "Package Geometry/Pastemask Top")
		(15 "B.Paste" user "Package Geometry/Pastemask Bottom")
		(5 "F.SilkS" user "Ref Des/Silkscreen Top")
		(7 "B.SilkS" user "Ref Des/Silkscreen Bottom")
		(1 "F.Mask" user "Board Geometry/Soldermask Top")
		(3 "B.Mask" user "Board Geometry/Soldermask Bottom")
		(17 "Dwgs.User" user "User.Drawings")
		(19 "Cmts.User" user "User.Comments")
		(21 "Eco1.User" user "User.Eco1")
		(23 "Eco2.User" user "User.Eco2")
		(25 "Edge.Cuts" user "Board Geometry/Outline")
		(27 "Margin" user)
		(31 "F.CrtYd" user "Package Geometry/Place Bound Top")
		(29 "B.CrtYd" user "Package Geometry/Place Bound Bottom")
		(35 "F.Fab" user "Ref Des/Assembly Top")
		(33 "B.Fab" user "Ref Des/Assembly Bottom")
	)
	(footprint ""
		(layer "F.Cu")
		(at 69.741034 -380.385828)
		(property "Reference" "C806"
			(at 0 0 0)
			(layer "F.SilkS")
			(hide yes)
			(effects
				(font
					(size 1.27 1.27)
				)
			)
		)
		(property "Value" ""
			(at 0 0 0)
			(layer "F.Fab")
			(effects
				(font
					(size 1.27 1.27)
				)
			)
		)
		(duplicate_pad_numbers_are_jumpers no)
		(fp_line
			(start -0.299974 -0.150114)
			(end 0.299974 -0.150114)
			(stroke
				(width 0.1)
				(type default)
			)
			(layer "F.Fab")
		)
		(fp_line
			(start -0.299974 0.150114)
			(end -0.299974 -0.150114)
			(stroke
				(width 0.1)
				(type default)
			)
			(layer "F.Fab")
		)
		(fp_line
			(start 0.299974 -0.150114)
			(end 0.299974 0.150114)
			(stroke
				(width 0.1)
				(type default)
			)
			(layer "F.Fab")
		)
		(fp_line
			(start 0.299974 0.150114)
			(end -0.299974 0.150114)
			(stroke
				(width 0.1)
				(type default)
			)
			(layer "F.Fab")
		)
		(pad "1" smd rect
			(at -0.2667 0)
			(size 0.3048 0.381)
			(layers "F.Cu" "F.Mask" "F.Paste")
			(net "P5E_CPU1_P0_TX_C_DN<15>")
		)
		(pad "2" smd rect
			(at 0.2667 0)
			(size 0.3048 0.381)
			(layers "F.Cu" "F.Mask" "F.Paste")
			(net "P5E_CPU1_P0_TX_DN<15>")
		)
	)
	(footprint ""
		(layer "F.Cu")
		(at 414.337246 -360.7943)
		(property "Reference" "R8458"
			(at 0 0 0)
			(layer "F.SilkS")
			(hide yes)
			(effects
				(font
					(size 1.27 1.27)
				)
			)
		)
		(property "Value" ""
			(at 0 0 0)
			(layer "F.Fab")
			(effects
				(font
					(size 1.27 1.27)
				)
			)
		)
		(duplicate_pad_numbers_are_jumpers no)
		(fp_line
			(start -0.7874 -0.4064)
			(end 0.7874 -0.4064)
			(stroke
				(width 0.1524)
				(type default)
			)
			(layer "F.SilkS")
		)
		(fp_line
			(start -0.7874 0.4064)
			(end -0.7874 -0.4064)
			(stroke
				(width 0.1524)
				(type default)
			)
			(layer "F.SilkS")
		)
		(fp_line
			(start 0.7874 -0.4064)
			(end 0.7874 0.4064)
			(stroke
				(width 0.1524)
				(type default)
			)
			(layer "F.SilkS")
		)
		(fp_line
			(start 0.7874 0.4064)
			(end -0.7874 0.4064)
			(stroke
				(width 0.1524)
				(type default)
			)
			(layer "F.SilkS")
		)
		(fp_line
			(start -0.67945 -0.305054)
			(end -0.12065 -0.305054)
			(stroke
				(width 0.1)
				(type default)
			)
			(layer "F.Fab")
		)
		(fp_line
			(start -0.67945 0.3048)
			(end -0.67945 -0.305054)
			(stroke
				(width 0.1)
				(type default)
			)
			(layer "F.Fab")
		)
		(fp_line
			(start -0.12065 -0.305054)
			(end -0.12065 -0.2794)
			(stroke
				(width 0.1)
				(type default)
			)
			(layer "F.Fab")
		)
		(fp_line
			(start -0.12065 -0.2794)
			(end 0.12065 -0.2794)
			(stroke
				(width 0.1)
				(type default)
			)
			(layer "F.Fab")
		)
		(fp_line
			(start -0.12065 0.2794)
			(end -0.12065 0.3048)
			(stroke
				(width 0.1)
				(type default)
			)
			(layer "F.Fab")
		)
		(fp_line
			(start -0.12065 0.3048)
			(end -0.67945 0.3048)
			(stroke
				(width 0.1)
				(type default)
			)
			(layer "F.Fab")
		)
		(fp_line
			(start 0.120396 0.2794)
			(end -0.12065 0.2794)
			(stroke
				(width 0.1)
				(type default)
			)
			(layer "F.Fab")
		)
		(fp_line
			(start 0.120396 0.3048)
			(end 0.120396 0.2794)
			(stroke
				(width 0.1)
				(type default)
			)
			(layer "F.Fab")
		)
		(fp_line
			(start 0.12065 -0.3048)
			(end 0.67945 -0.3048)
			(stroke
				(width 0.1)
				(type default)
			)
			(layer "F.Fab")
		)
		(fp_line
			(start 0.12065 -0.2794)
			(end 0.12065 -0.3048)
			(stroke
				(width 0.1)
				(type default)
			)
			(layer "F.Fab")
		)
		(fp_line
			(start 0.67945 -0.3048)
			(end 0.67945 0.3048)
			(stroke
				(width 0.1)
				(type default)
			)
			(layer "F.Fab")
		)
		(fp_line
			(start 0.67945 0.3048)
			(end 0.120396 0.3048)
			(stroke
				(width 0.1)
				(type default)
			)
			(layer "F.Fab")
		)
		(pad "1" smd circle
			(at -0.40005 0)
			(size 0 0)
			(layers "F.Cu" "F.Mask" "F.Paste")
			(net "P3V3_AUX")
		)
		(pad "2" smd circle
			(at 0.40005 0)
			(size 0 0)
			(layers "F.Cu" "F.Mask" "F.Paste")
			(net "PVDD11_S3_P0_VDDIO")
		)
	)
	(footprint ""
		(layer "F.Cu")
		(at 423.796206 -404.0124 -90)
		(property "Reference" "R1047"
			(at 0 0 270)
			(layer "F.SilkS")
			(hide yes)
			(effects
				(font
					(size 1.27 1.27)
				)
			)
		)
		(property "Value" ""
			(at 0 0 270)
			(layer "F.Fab")
			(effects
				(font
					(size 1.27 1.27)
				)
			)
		)
		(duplicate_pad_numbers_are_jumpers no)
		(fp_line
			(start -0.32512 0.175006)
			(end -0.32512 -0.175006)
			(stroke
				(width 0.1)
				(type default)
			)
			(layer "F.Fab")
		)
		(fp_line
			(start 0.32512 0.175006)
			(end -0.32512 0.175006)
			(stroke
				(width 0.1)
				(type default)
			)
			(layer "F.Fab")
		)
		(fp_line
			(start -0.32512 -0.175006)
			(end 0.32512 -0.175006)
			(stroke
				(width 0.1)
				(type default)
			)
			(layer "F.Fab")
		)
		(fp_line
			(start 0.32512 -0.175006)
			(end 0.32512 0.175006)
			(stroke
				(width 0.1)
				(type default)
			)
			(layer "F.Fab")
		)
		(pad "1" smd rect
			(at -0.2667 0 270)
			(size 0.3048 0.381)
			(layers "F.Cu" "F.Mask" "F.Paste")
			(net "RST_RT_CPU0_P2_PERST_N")
		)
		(pad "2" smd rect
			(at 0.2667 0 90)
			(size 0.3048 0.381)
			(layers "F.Cu" "F.Mask" "F.Paste")
			(net "RST_RT_CPU0_P2_PERST_R_N")
		)
	)
	(footprint ""
		(layer "F.Cu")
		(at 89.564972 -68.02374 90)
		(property "Reference" "PC2142"
			(at 0 0 90)
			(layer "F.SilkS")
			(hide yes)
			(effects
				(font
					(size 1.27 1.27)
				)
			)
		)
		(property "Value" ""
			(at 0 0 90)
			(layer "F.Fab")
			(effects
				(font
					(size 1.27 1.27)
				)
			)
		)
		(duplicate_pad_numbers_are_jumpers no)
		(fp_line
			(start 1.524 -0.762)
			(end 1.524 0.762)
			(stroke
				(width 0.1524)
				(type default)
			)
			(layer "F.SilkS")
		)
		(fp_line
			(start -1.524 -0.762)
			(end 1.524 -0.762)
			(stroke
				(width 0.1524)
				(type default)
			)
			(layer "F.SilkS")
		)
		(fp_line
			(start 1.524 0.762)
			(end -1.524 0.762)
			(stroke
				(width 0.1524)
				(type default)
			)
			(layer "F.SilkS")
		)
		(fp_line
			(start -1.524 0.762)
			(end -1.524 -0.762)
			(stroke
				(width 0.1524)
				(type default)
			)
			(layer "F.SilkS")
		)
		(fp_line
			(start 1.1049 -0.724916)
			(end -1.1049 -0.724916)
			(stroke
				(width 0.1)
				(type default)
			)
			(layer "F.Fab")
		)
		(fp_line
			(start -1.1049 -0.724916)
			(end -1.1049 0.724916)
			(stroke
				(width 0.1)
				(type default)
			)
			(layer "F.Fab")
		)
		(fp_line
			(start 1.1049 0.724916)
			(end 1.1049 -0.724916)
			(stroke
				(width 0.1)
				(type default)
			)
			(layer "F.Fab")
		)
		(fp_line
			(start -1.1049 0.724916)
			(end 1.1049 0.724916)
			(stroke
				(width 0.1)
				(type default)
			)
			(layer "F.Fab")
		)
		(pad "1" smd rect
			(at -0.889 0 270)
			(size 1.016 1.27)
			(layers "F.Cu" "F.Mask" "F.Paste")
			(net "P3V3_OCP_V3_2_R")
		)
		(pad "2" smd rect
			(at 0.889 0 270)
			(size 1.016 1.27)
			(layers "F.Cu" "F.Mask" "F.Paste")
			(net "GND")
		)
	)
)
